(kicad_pcb
	(version 20260206)
	(generator "pcbnew")
	(generator_version "10.0")
	(general
		(thickness 1.6)
		(legacy_teardrops no)
	)
	(paper "A4")
	(title_block
		(title "04192023_DAF0TMB3IC0_F0TG_MB_C_brd_V02_OCP.brd")
		(comment 1 "Grand Teton / footprints 5376-5381 of 8354")
	)
	(layers
		(0 "F.Cu" signal "TOP")
		(4 "In1.Cu" signal "GND")
		(6 "In2.Cu" signal "IN1")
		(8 "In3.Cu" signal "GND1")
		(10 "In4.Cu" signal "IN2")
		(12 "In5.Cu" signal "GND2")
		(14 "In6.Cu" signal "IN3")
		(16 "In7.Cu" signal "GND3")
		(18 "In8.Cu" signal "VCC")
		(20 "In9.Cu" signal "VCC1")
		(22 "In10.Cu" signal "GND4")
		(24 "In11.Cu" signal "IN4")
		(26 "In12.Cu" signal "GND5")
		(28 "In13.Cu" signal "IN5")
		(30 "In14.Cu" signal "GND6")
		(32 "In15.Cu" signal "IN6")
		(34 "In16.Cu" signal "GND7")
		(2 "B.Cu" signal "BOTTOM")
		(9 "F.Adhes" user "F.Adhesive")
		(11 "B.Adhes" user "B.Adhesive")
		(13 "F.Paste" user "Package Geometry/Pastemask Top")
		(15 "B.Paste" user "Package Geometry/Pastemask Bottom")
		(5 "F.SilkS" user "Ref Des/Silkscreen Top")
		(7 "B.SilkS" user "Ref Des/Silkscreen Bottom")
		(1 "F.Mask" user "Board Geometry/Soldermask Top")
		(3 "B.Mask" user "Board Geometry/Soldermask Bottom")
		(17 "Dwgs.User" user "User.Drawings")
		(19 "Cmts.User" user "User.Comments")
		(21 "Eco1.User" user "User.Eco1")
		(23 "Eco2.User" user "User.Eco2")
		(25 "Edge.Cuts" user "Board Geometry/Outline")
		(27 "Margin" user)
		(31 "F.CrtYd" user "Package Geometry/Place Bound Top")
		(29 "B.CrtYd" user "Package Geometry/Place Bound Bottom")
		(35 "F.Fab" user "Ref Des/Assembly Top")
		(33 "B.Fab" user "Ref Des/Assembly Bottom")
	)
	(footprint ""
		(layer "B.Cu")
		(at 352.723958 -249.36831 180)
		(property "Reference" "C278"
			(at 0 0 0)
			(layer "B.SilkS")
			(hide yes)
			(effects
				(font
					(size 1.27 1.27)
				)
				(justify mirror)
			)
		)
		(property "Value" ""
			(at 0 0 0)
			(layer "B.Fab")
			(effects
				(font
					(size 1.27 1.27)
				)
				(justify mirror)
			)
		)
		(duplicate_pad_numbers_are_jumpers no)
		(fp_line
			(start 0.7874 0.4064)
			(end 0.7874 -0.4064)
			(stroke
				(width 0.1524)
				(type default)
			)
			(layer "B.SilkS")
		)
		(fp_line
			(start 0.7874 -0.4064)
			(end -0.7874 -0.4064)
			(stroke
				(width 0.1524)
				(type default)
			)
			(layer "B.SilkS")
		)
		(fp_line
			(start -0.7874 0.4064)
			(end 0.7874 0.4064)
			(stroke
				(width 0.1524)
				(type default)
			)
			(layer "B.SilkS")
		)
		(fp_line
			(start -0.7874 -0.4064)
			(end -0.7874 0.4064)
			(stroke
				(width 0.1524)
				(type default)
			)
			(layer "B.SilkS")
		)
		(fp_line
			(start 0.67945 0.3048)
			(end 0.67945 -0.305054)
			(stroke
				(width 0.1)
				(type default)
			)
			(layer "B.Fab")
		)
		(fp_line
			(start 0.67945 -0.305054)
			(end 0.12065 -0.305054)
			(stroke
				(width 0.1)
				(type default)
			)
			(layer "B.Fab")
		)
		(fp_line
			(start 0.12065 0.3048)
			(end 0.67945 0.3048)
			(stroke
				(width 0.1)
				(type default)
			)
			(layer "B.Fab")
		)
		(fp_line
			(start 0.12065 0.2794)
			(end 0.12065 0.3048)
			(stroke
				(width 0.1)
				(type default)
			)
			(layer "B.Fab")
		)
		(fp_line
			(start 0.12065 -0.2794)
			(end -0.12065 -0.2794)
			(stroke
				(width 0.1)
				(type default)
			)
			(layer "B.Fab")
		)
		(fp_line
			(start 0.12065 -0.305054)
			(end 0.12065 -0.2794)
			(stroke
				(width 0.1)
				(type default)
			)
			(layer "B.Fab")
		)
		(fp_line
			(start -0.120396 0.3048)
			(end -0.120396 0.2794)
			(stroke
				(width 0.1)
				(type default)
			)
			(layer "B.Fab")
		)
		(fp_line
			(start -0.120396 0.2794)
			(end 0.12065 0.2794)
			(stroke
				(width 0.1)
				(type default)
			)
			(layer "B.Fab")
		)
		(fp_line
			(start -0.12065 -0.2794)
			(end -0.12065 -0.3048)
			(stroke
				(width 0.1)
				(type default)
			)
			(layer "B.Fab")
		)
		(fp_line
			(start -0.12065 -0.3048)
			(end -0.67945 -0.3048)
			(stroke
				(width 0.1)
				(type default)
			)
			(layer "B.Fab")
		)
		(fp_line
			(start -0.67945 0.3048)
			(end -0.120396 0.3048)
			(stroke
				(width 0.1)
				(type default)
			)
			(layer "B.Fab")
		)
		(fp_line
			(start -0.67945 -0.3048)
			(end -0.67945 0.3048)
			(stroke
				(width 0.1)
				(type default)
			)
			(layer "B.Fab")
		)
		(pad "1" smd circle
			(at 0.40005 0)
			(size 0 0)
			(layers "B.Cu" "B.Mask" "B.Paste")
			(net "PVDDCR_CPU0_P0")
		)
		(pad "2" smd circle
			(at -0.40005 0)
			(size 0 0)
			(layers "B.Cu" "B.Mask" "B.Paste")
			(net "GND")
		)
	)
	(footprint ""
		(layer "B.Cu")
		(at 349.834454 -261.17931)
		(property "Reference" "C2581"
			(at 0 0 0)
			(layer "B.SilkS")
			(hide yes)
			(effects
				(font
					(size 1.27 1.27)
				)
				(justify mirror)
			)
		)
		(property "Value" ""
			(at 0 0 0)
			(layer "B.Fab")
			(effects
				(font
					(size 1.27 1.27)
				)
				(justify mirror)
			)
		)
		(duplicate_pad_numbers_are_jumpers no)
		(fp_line
			(start -0.7874 -0.4064)
			(end -0.7874 0.4064)
			(stroke
				(width 0.1524)
				(type default)
			)
			(layer "B.SilkS")
		)
		(fp_line
			(start -0.7874 0.4064)
			(end 0.7874 0.4064)
			(stroke
				(width 0.1524)
				(type default)
			)
			(layer "B.SilkS")
		)
		(fp_line
			(start 0.7874 -0.4064)
			(end -0.7874 -0.4064)
			(stroke
				(width 0.1524)
				(type default)
			)
			(layer "B.SilkS")
		)
		(fp_line
			(start 0.7874 0.4064)
			(end 0.7874 -0.4064)
			(stroke
				(width 0.1524)
				(type default)
			)
			(layer "B.SilkS")
		)
		(fp_line
			(start -0.67945 -0.3048)
			(end -0.67945 0.3048)
			(stroke
				(width 0.1)
				(type default)
			)
			(layer "B.Fab")
		)
		(fp_line
			(start -0.67945 0.3048)
			(end -0.120396 0.3048)
			(stroke
				(width 0.1)
				(type default)
			)
			(layer "B.Fab")
		)
		(fp_line
			(start -0.12065 -0.3048)
			(end -0.67945 -0.3048)
			(stroke
				(width 0.1)
				(type default)
			)
			(layer "B.Fab")
		)
		(fp_line
			(start -0.12065 -0.2794)
			(end -0.12065 -0.3048)
			(stroke
				(width 0.1)
				(type default)
			)
			(layer "B.Fab")
		)
		(fp_line
			(start -0.120396 0.2794)
			(end 0.12065 0.2794)
			(stroke
				(width 0.1)
				(type default)
			)
			(layer "B.Fab")
		)
		(fp_line
			(start -0.120396 0.3048)
			(end -0.120396 0.2794)
			(stroke
				(width 0.1)
				(type default)
			)
			(layer "B.Fab")
		)
		(fp_line
			(start 0.12065 -0.305054)
			(end 0.12065 -0.2794)
			(stroke
				(width 0.1)
				(type default)
			)
			(layer "B.Fab")
		)
		(fp_line
			(start 0.12065 -0.2794)
			(end -0.12065 -0.2794)
			(stroke
				(width 0.1)
				(type default)
			)
			(layer "B.Fab")
		)
		(fp_line
			(start 0.12065 0.2794)
			(end 0.12065 0.3048)
			(stroke
				(width 0.1)
				(type default)
			)
			(layer "B.Fab")
		)
		(fp_line
			(start 0.12065 0.3048)
			(end 0.67945 0.3048)
			(stroke
				(width 0.1)
				(type default)
			)
			(layer "B.Fab")
		)
		(fp_line
			(start 0.67945 -0.305054)
			(end 0.12065 -0.305054)
			(stroke
				(width 0.1)
				(type default)
			)
			(layer "B.Fab")
		)
		(fp_line
			(start 0.67945 0.3048)
			(end 0.67945 -0.305054)
			(stroke
				(width 0.1)
				(type default)
			)
			(layer "B.Fab")
		)
		(pad "1" smd circle
			(at 0.40005 0 180)
			(size 0 0)
			(layers "B.Cu" "B.Mask" "B.Paste")
			(net "PVDDCR_SOC_P0")
		)
		(pad "2" smd circle
			(at -0.40005 0 180)
			(size 0 0)
			(layers "B.Cu" "B.Mask" "B.Paste")
			(net "GND")
		)
	)
	(footprint ""
		(layer "B.Cu")
		(at 204.03312 -331.027786 -90)
		(property "Reference" "PC130"
			(at 0 0 90)
			(layer "B.SilkS")
			(hide yes)
			(effects
				(font
					(size 1.27 1.27)
				)
				(justify mirror)
			)
		)
		(property "Value" ""
			(at 0 0 90)
			(layer "B.Fab")
			(effects
				(font
					(size 1.27 1.27)
				)
				(justify mirror)
			)
		)
		(duplicate_pad_numbers_are_jumpers no)
		(fp_line
			(start -1.524 0.762)
			(end 1.524 0.762)
			(stroke
				(width 0.1524)
				(type default)
			)
			(layer "B.SilkS")
		)
		(fp_line
			(start 1.524 0.762)
			(end 1.524 -0.762)
			(stroke
				(width 0.1524)
				(type default)
			)
			(layer "B.SilkS")
		)
		(fp_line
			(start -1.524 -0.762)
			(end -1.524 0.762)
			(stroke
				(width 0.1524)
				(type default)
			)
			(layer "B.SilkS")
		)
		(fp_line
			(start 1.524 -0.762)
			(end -1.524 -0.762)
			(stroke
				(width 0.1524)
				(type default)
			)
			(layer "B.SilkS")
		)
		(fp_line
			(start -1.1049 0.724916)
			(end -1.1049 -0.724916)
			(stroke
				(width 0.1)
				(type default)
			)
			(layer "B.Fab")
		)
		(fp_line
			(start 1.1049 0.724916)
			(end -1.1049 0.724916)
			(stroke
				(width 0.1)
				(type default)
			)
			(layer "B.Fab")
		)
		(fp_line
			(start -1.1049 -0.724916)
			(end 1.1049 -0.724916)
			(stroke
				(width 0.1)
				(type default)
			)
			(layer "B.Fab")
		)
		(fp_line
			(start 1.1049 -0.724916)
			(end 1.1049 0.724916)
			(stroke
				(width 0.1)
				(type default)
			)
			(layer "B.Fab")
		)
		(pad "1" smd rect
			(at 0.889 0 270)
			(size 1.016 1.27)
			(layers "B.Cu" "B.Mask" "B.Paste")
			(net "PVDD_33_S5")
		)
		(pad "2" smd rect
			(at -0.889 0 270)
			(size 1.016 1.27)
			(layers "B.Cu" "B.Mask" "B.Paste")
			(net "GND")
		)
	)
	(footprint ""
		(layer "B.Cu")
		(at 54.591204 -390.560052 90)
		(property "Reference" "C261"
			(at 0 0 90)
			(layer "B.SilkS")
			(hide yes)
			(effects
				(font
					(size 1.27 1.27)
				)
				(justify mirror)
			)
		)
		(property "Value" ""
			(at 0 0 90)
			(layer "B.Fab")
			(effects
				(font
					(size 1.27 1.27)
				)
				(justify mirror)
			)
		)
		(duplicate_pad_numbers_are_jumpers no)
		(fp_line
			(start 0.7874 -0.4064)
			(end -0.7874 -0.4064)
			(stroke
				(width 0.1524)
				(type default)
			)
			(layer "B.SilkS")
		)
		(fp_line
			(start -0.7874 -0.4064)
			(end -0.7874 0.4064)
			(stroke
				(width 0.1524)
				(type default)
			)
			(layer "B.SilkS")
		)
		(fp_line
			(start 0.7874 0.4064)
			(end 0.7874 -0.4064)
			(stroke
				(width 0.1524)
				(type default)
			)
			(layer "B.SilkS")
		)
		(fp_line
			(start -0.7874 0.4064)
			(end 0.7874 0.4064)
			(stroke
				(width 0.1524)
				(type default)
			)
			(layer "B.SilkS")
		)
		(fp_line
			(start 0.67945 -0.305054)
			(end 0.12065 -0.305054)
			(stroke
				(width 0.1)
				(type default)
			)
			(layer "B.Fab")
		)
		(fp_line
			(start 0.12065 -0.305054)
			(end 0.12065 -0.2794)
			(stroke
				(width 0.1)
				(type default)
			)
			(layer "B.Fab")
		)
		(fp_line
			(start -0.12065 -0.3048)
			(end -0.67945 -0.3048)
			(stroke
				(width 0.1)
				(type default)
			)
			(layer "B.Fab")
		)
		(fp_line
			(start -0.67945 -0.3048)
			(end -0.67945 0.3048)
			(stroke
				(width 0.1)
				(type default)
			)
			(layer "B.Fab")
		)
		(fp_line
			(start 0.12065 -0.2794)
			(end -0.12065 -0.2794)
			(stroke
				(width 0.1)
				(type default)
			)
			(layer "B.Fab")
		)
		(fp_line
			(start -0.12065 -0.2794)
			(end -0.12065 -0.3048)
			(stroke
				(width 0.1)
				(type default)
			)
			(layer "B.Fab")
		)
		(fp_line
			(start 0.12065 0.2794)
			(end 0.12065 0.3048)
			(stroke
				(width 0.1)
				(type default)
			)
			(layer "B.Fab")
		)
		(fp_line
			(start -0.120396 0.2794)
			(end 0.12065 0.2794)
			(stroke
				(width 0.1)
				(type default)
			)
			(layer "B.Fab")
		)
		(fp_line
			(start 0.67945 0.3048)
			(end 0.67945 -0.305054)
			(stroke
				(width 0.1)
				(type default)
			)
			(layer "B.Fab")
		)
		(fp_line
			(start 0.12065 0.3048)
			(end 0.67945 0.3048)
			(stroke
				(width 0.1)
				(type default)
			)
			(layer "B.Fab")
		)
		(fp_line
			(start -0.120396 0.3048)
			(end -0.120396 0.2794)
			(stroke
				(width 0.1)
				(type default)
			)
			(layer "B.Fab")
		)
		(fp_line
			(start -0.67945 0.3048)
			(end -0.120396 0.3048)
			(stroke
				(width 0.1)
				(type default)
			)
			(layer "B.Fab")
		)
		(pad "1" smd circle
			(at 0.40005 0 270)
			(size 0 0)
			(layers "B.Cu" "B.Mask" "B.Paste")
			(net "P0V9_CPU1_RT_2D")
		)
		(pad "2" smd circle
			(at -0.40005 0 270)
			(size 0 0)
			(layers "B.Cu" "B.Mask" "B.Paste")
			(net "GND")
		)
	)
	(footprint ""
		(layer "B.Cu")
		(at 141.977872 -64.04229 90)
		(property "Reference" "R14"
			(at 0 0 90)
			(layer "B.SilkS")
			(hide yes)
			(effects
				(font
					(size 1.27 1.27)
				)
				(justify mirror)
			)
		)
		(property "Value" ""
			(at 0 0 90)
			(layer "B.Fab")
			(effects
				(font
					(size 1.27 1.27)
				)
				(justify mirror)
			)
		)
		(duplicate_pad_numbers_are_jumpers no)
		(fp_line
			(start 0.7874 -0.4064)
			(end -0.7874 -0.4064)
			(stroke
				(width 0.1524)
				(type default)
			)
			(layer "B.SilkS")
		)
		(fp_line
			(start -0.7874 -0.4064)
			(end -0.7874 0.4064)
			(stroke
				(width 0.1524)
				(type default)
			)
			(layer "B.SilkS")
		)
		(fp_line
			(start 0.7874 0.4064)
			(end 0.7874 -0.4064)
			(stroke
				(width 0.1524)
				(type default)
			)
			(layer "B.SilkS")
		)
		(fp_line
			(start -0.7874 0.4064)
			(end 0.7874 0.4064)
			(stroke
				(width 0.1524)
				(type default)
			)
			(layer "B.SilkS")
		)
		(fp_line
			(start 0.67945 -0.305054)
			(end 0.12065 -0.305054)
			(stroke
				(width 0.1)
				(type default)
			)
			(layer "B.Fab")
		)
		(fp_line
			(start 0.12065 -0.305054)
			(end 0.12065 -0.2794)
			(stroke
				(width 0.1)
				(type default)
			)
			(layer "B.Fab")
		)
		(fp_line
			(start -0.12065 -0.3048)
			(end -0.67945 -0.3048)
			(stroke
				(width 0.1)
				(type default)
			)
			(layer "B.Fab")
		)
		(fp_line
			(start -0.67945 -0.3048)
			(end -0.67945 0.3048)
			(stroke
				(width 0.1)
				(type default)
			)
			(layer "B.Fab")
		)
		(fp_line
			(start 0.12065 -0.2794)
			(end -0.12065 -0.2794)
			(stroke
				(width 0.1)
				(type default)
			)
			(layer "B.Fab")
		)
		(fp_line
			(start -0.12065 -0.2794)
			(end -0.12065 -0.3048)
			(stroke
				(width 0.1)
				(type default)
			)
			(layer "B.Fab")
		)
		(fp_line
			(start 0.12065 0.2794)
			(end 0.12065 0.3048)
			(stroke
				(width 0.1)
				(type default)
			)
			(layer "B.Fab")
		)
		(fp_line
			(start -0.120396 0.2794)
			(end 0.12065 0.2794)
			(stroke
				(width 0.1)
				(type default)
			)
			(layer "B.Fab")
		)
		(fp_line
			(start 0.67945 0.3048)
			(end 0.67945 -0.305054)
			(stroke
				(width 0.1)
				(type default)
			)
			(layer "B.Fab")
		)
		(fp_line
			(start 0.12065 0.3048)
			(end 0.67945 0.3048)
			(stroke
				(width 0.1)
				(type default)
			)
			(layer "B.Fab")
		)
		(fp_line
			(start -0.120396 0.3048)
			(end -0.120396 0.2794)
			(stroke
				(width 0.1)
				(type default)
			)
			(layer "B.Fab")
		)
		(fp_line
			(start -0.67945 0.3048)
			(end -0.120396 0.3048)
			(stroke
				(width 0.1)
				(type default)
			)
			(layer "B.Fab")
		)
		(pad "1" smd circle
			(at 0.40005 0 270)
			(size 0 0)
			(layers "B.Cu" "B.Mask" "B.Paste")
			(net "JTAG_PLD_TMS")
		)
		(pad "2" smd circle
			(at -0.40005 0 270)
			(size 0 0)
			(layers "B.Cu" "B.Mask" "B.Paste")
			(net "JTAG_SCM_PLD_TMS")
		)
	)
	(footprint ""
		(layer "B.Cu")
		(at 200.952608 -121.753376 180)
		(property "Reference" "R4563"
			(at 0 0 0)
			(layer "B.SilkS")
			(hide yes)
			(effects
				(font
					(size 1.27 1.27)
				)
				(justify mirror)
			)
		)
		(property "Value" ""
			(at 0 0 0)
			(layer "B.Fab")
			(effects
				(font
					(size 1.27 1.27)
				)
				(justify mirror)
			)
		)
		(duplicate_pad_numbers_are_jumpers no)
		(fp_line
			(start 0.7874 0.4064)
			(end 0.7874 -0.4064)
			(stroke
				(width 0.1524)
				(type default)
			)
			(layer "B.SilkS")
		)
		(fp_line
			(start 0.7874 -0.4064)
			(end -0.7874 -0.4064)
			(stroke
				(width 0.1524)
				(type default)
			)
			(layer "B.SilkS")
		)
		(fp_line
			(start -0.7874 0.4064)
			(end 0.7874 0.4064)
			(stroke
				(width 0.1524)
				(type default)
			)
			(layer "B.SilkS")
		)
		(fp_line
			(start -0.7874 -0.4064)
			(end -0.7874 0.4064)
			(stroke
				(width 0.1524)
				(type default)
			)
			(layer "B.SilkS")
		)
		(fp_line
			(start 0.67945 0.3048)
			(end 0.67945 -0.305054)
			(stroke
				(width 0.1)
				(type default)
			)
			(layer "B.Fab")
		)
		(fp_line
			(start 0.67945 -0.305054)
			(end 0.12065 -0.305054)
			(stroke
				(width 0.1)
				(type default)
			)
			(layer "B.Fab")
		)
		(fp_line
			(start 0.12065 0.3048)
			(end 0.67945 0.3048)
			(stroke
				(width 0.1)
				(type default)
			)
			(layer "B.Fab")
		)
		(fp_line
			(start 0.12065 0.2794)
			(end 0.12065 0.3048)
			(stroke
				(width 0.1)
				(type default)
			)
			(layer "B.Fab")
		)
		(fp_line
			(start 0.12065 -0.2794)
			(end -0.12065 -0.2794)
			(stroke
				(width 0.1)
				(type default)
			)
			(layer "B.Fab")
		)
		(fp_line
			(start 0.12065 -0.305054)
			(end 0.12065 -0.2794)
			(stroke
				(width 0.1)
				(type default)
			)
			(layer "B.Fab")
		)
		(fp_line
			(start -0.120396 0.3048)
			(end -0.120396 0.2794)
			(stroke
				(width 0.1)
				(type default)
			)
			(layer "B.Fab")
		)
		(fp_line
			(start -0.120396 0.2794)
			(end 0.12065 0.2794)
			(stroke
				(width 0.1)
				(type default)
			)
			(layer "B.Fab")
		)
		(fp_line
			(start -0.12065 -0.2794)
			(end -0.12065 -0.3048)
			(stroke
				(width 0.1)
				(type default)
			)
			(layer "B.Fab")
		)
		(fp_line
			(start -0.12065 -0.3048)
			(end -0.67945 -0.3048)
			(stroke
				(width 0.1)
				(type default)
			)
			(layer "B.Fab")
		)
		(fp_line
			(start -0.67945 0.3048)
			(end -0.120396 0.3048)
			(stroke
				(width 0.1)
				(type default)
			)
			(layer "B.Fab")
		)
		(fp_line
			(start -0.67945 -0.3048)
			(end -0.67945 0.3048)
			(stroke
				(width 0.1)
				(type default)
			)
			(layer "B.Fab")
		)
		(pad "1" smd circle
			(at 0.40005 0)
			(size 0 0)
			(layers "B.Cu" "B.Mask" "B.Paste")
			(net "SWB_HSC_PWRGD_ISO_R")
		)
		(pad "2" smd circle
			(at -0.40005 0)
			(size 0 0)
			(layers "B.Cu" "B.Mask" "B.Paste")
			(net "SWB_HSC_PWRGD_ISO")
		)
	)
)
